(kicad_pcb
	(version 20260206)
	(generator "pcbnew")
	(generator_version "10.0")
	(general
		(thickness 1.6)
		(legacy_teardrops no)
	)
	(paper "A4")
	(title_block
		(title "Wiwynn_Tioga_Pass_MB.brd")
		(comment 1 "Tioga Pass / footprints 2791-2798 of 4770")
	)
	(layers
		(0 "F.Cu" signal "TOP")
		(4 "In1.Cu" signal "L2GND")
		(6 "In2.Cu" signal "L3")
		(8 "In3.Cu" signal "L4GND")
		(10 "In4.Cu" signal "L5")
		(12 "In5.Cu" signal "L6GND")
		(14 "In6.Cu" signal "L7VCC")
		(16 "In7.Cu" signal "L8VCC")
		(18 "In8.Cu" signal "L9GND")
		(20 "In9.Cu" signal "L10")
		(22 "In10.Cu" signal "L11GND")
		(24 "In11.Cu" signal "L12")
		(26 "In12.Cu" signal "L13GND")
		(2 "B.Cu" signal "BOTTOM")
		(9 "F.Adhes" user "F.Adhesive")
		(11 "B.Adhes" user "B.Adhesive")
		(13 "F.Paste" user "Package Geometry/Pastemask Top")
		(15 "B.Paste" user "Package Geometry/Pastemask Bottom")
		(5 "F.SilkS" user "Ref Des/Silkscreen Top")
		(7 "B.SilkS" user "Ref Des/Silkscreen Bottom")
		(1 "F.Mask" user "Board Geometry/Soldermask Top")
		(3 "B.Mask" user "Board Geometry/Soldermask Bottom")
		(17 "Dwgs.User" user "User.Drawings")
		(19 "Cmts.User" user "User.Comments")
		(21 "Eco1.User" user "User.Eco1")
		(23 "Eco2.User" user "User.Eco2")
		(25 "Edge.Cuts" user "Board Geometry/Outline")
		(27 "Margin" user)
		(31 "F.CrtYd" user "Package Geometry/Place Bound Top")
		(29 "B.CrtYd" user "Package Geometry/Place Bound Bottom")
		(35 "F.Fab" user "Ref Des/Assembly Top")
		(33 "B.Fab" user "Ref Des/Assembly Bottom")
	)
	(footprint ""
		(layer "B.Cu")
		(at 386.1816 -104.5464 90)
		(property "Reference" "C3N25"
			(at 0 0 90)
			(layer "B.SilkS")
			(hide yes)
			(effects
				(font
					(size 1.27 1.27)
				)
				(justify mirror)
			)
		)
		(property "Value" ""
			(at 0 0 90)
			(layer "B.Fab")
			(effects
				(font
					(size 1.27 1.27)
				)
				(justify mirror)
			)
		)
		(duplicate_pad_numbers_are_jumpers no)
		(fp_rect
			(start 0.2794 0.9144)
			(end -0.2794 -0.1143)
			(stroke
				(width 0)
				(type default)
			)
			(fill no)
			(layer "B.CrtYd")
		)
		(fp_line
			(start 0.2794 -0.1143)
			(end -0.2794 -0.1143)
			(stroke
				(width 0.1)
				(type default)
			)
			(layer "B.Fab")
		)
		(fp_line
			(start -0.2794 -0.1143)
			(end -0.2794 0.9144)
			(stroke
				(width 0.1)
				(type default)
			)
			(layer "B.Fab")
		)
		(fp_line
			(start 0.2794 0.9144)
			(end 0.2794 -0.1143)
			(stroke
				(width 0.1)
				(type default)
			)
			(layer "B.Fab")
		)
		(fp_line
			(start -0.2794 0.9144)
			(end 0.2794 0.9144)
			(stroke
				(width 0.1)
				(type default)
			)
			(layer "B.Fab")
		)
		(pad "1" smd custom
			(at 0 0)
			(size 0.10414 0.10414)
			(layers "B.Cu" "B.Mask" "B.Paste")
			(net "P1V8_PCH_STBY")
			(options
				(clearance outline)
				(anchor circle)
			)
			(primitives
				(gr_poly
					(pts
						(xy -0.20828 -0.08636) (xy -0.20828 0.08636) (xy -0.08636 0.20828) (xy 0.086614 0.20828) (xy 0.20828 0.086614)
						(xy 0.20828 -0.08636) (xy 0.08636 -0.20828) (xy -0.08636 -0.20828)
					)
					(width 0)
					(fill yes)
				)
			)
		)
		(pad "2" smd custom
			(at 0 0.8001)
			(size 0.10414 0.10414)
			(layers "B.Cu" "B.Mask" "B.Paste")
			(net "GND")
			(options
				(clearance outline)
				(anchor circle)
			)
			(primitives
				(gr_poly
					(pts
						(xy -0.20828 -0.08636) (xy -0.20828 0.08636) (xy -0.08636 0.20828) (xy 0.086614 0.20828) (xy 0.20828 0.086614)
						(xy 0.20828 -0.08636) (xy 0.08636 -0.20828) (xy -0.08636 -0.20828)
					)
					(width 0)
					(fill yes)
				)
			)
		)
		(zone
			(layer "B.Cu")
			(hatch none 0.5)
			(connect_pads
				(clearance 0)
			)
			(min_thickness 0.25)
			(keepout
				(tracks not_allowed)
				(vias allowed)
				(pads allowed)
				(copperpour not_allowed)
				(footprints allowed)
			)
			(placement
				(enabled no)
				(sheetname "")
			)
			(fill
				(thermal_gap 0.5)
				(thermal_bridge_width 0.5)
				(island_removal_mode 0)
			)
			(polygon
				(pts
					(xy 386.39115 -104.63403) (xy 386.77215 -104.63403) (xy 386.77215 -104.45877) (xy 386.39115 -104.458516)
				)
			)
		)
		(zone
			(layer "B.Cu")
			(hatch none 0.5)
			(connect_pads
				(clearance 0)
			)
			(min_thickness 0.25)
			(keepout
				(tracks allowed)
				(vias not_allowed)
				(pads allowed)
				(copperpour not_allowed)
				(footprints allowed)
			)
			(placement
				(enabled no)
				(sheetname "")
			)
			(fill
				(thermal_gap 0.5)
				(thermal_bridge_width 0.5)
				(island_removal_mode 0)
			)
			(polygon
				(pts
					(xy 386.39115 -104.63403) (xy 386.77215 -104.63403) (xy 386.77215 -104.45877) (xy 386.39115 -104.458516)
				)
			)
		)
	)
	(footprint ""
		(layer "B.Cu")
		(at 439.6613 -147.955 180)
		(property "Reference" "R25W167"
			(at 0.8382 -0.67818 180)
			(unlocked yes)
			(layer "B.SilkS")
			(effects
				(font
					(size 0.4064 0.254)
					(thickness 0.1524)
				)
				(justify left mirror)
			)
		)
		(property "Value" ""
			(at 0 0 0)
			(layer "B.Fab")
			(effects
				(font
					(size 1.27 1.27)
				)
				(justify mirror)
			)
		)
		(duplicate_pad_numbers_are_jumpers no)
		(fp_poly
			(pts
				(xy 0.2794 -0.1016) (xy -0.2794 -0.1016) (xy -0.2794 0.9906) (xy 0.2794 0.9906)
			)
			(stroke
				(width 0)
				(type default)
			)
			(fill no)
			(layer "B.CrtYd")
		)
		(fp_line
			(start 0.2794 0.9906)
			(end -0.2794 0.9906)
			(stroke
				(width 0.1)
				(type default)
			)
			(layer "B.Fab")
		)
		(fp_line
			(start 0.2794 -0.1016)
			(end 0.2794 0.9906)
			(stroke
				(width 0.1)
				(type default)
			)
			(layer "B.Fab")
		)
		(fp_line
			(start -0.2794 0.9906)
			(end -0.2794 -0.1016)
			(stroke
				(width 0.1)
				(type default)
			)
			(layer "B.Fab")
		)
		(fp_line
			(start -0.2794 -0.1016)
			(end 0.2794 -0.1016)
			(stroke
				(width 0.1)
				(type default)
			)
			(layer "B.Fab")
		)
		(pad "1" smd rect
			(at 0 0)
			(size 0.508 0.508)
			(layers "B.Cu" "B.Mask" "B.Paste")
			(net "BMC_TCK_MUX_SEL")
		)
		(pad "2" smd rect
			(at 0 0.889)
			(size 0.508 0.508)
			(layers "B.Cu" "B.Mask" "B.Paste")
			(net "GND")
		)
		(zone
			(layer "B.Cu")
			(hatch none 0.5)
			(connect_pads
				(clearance 0)
			)
			(min_thickness 0.25)
			(keepout
				(tracks not_allowed)
				(vias allowed)
				(pads allowed)
				(copperpour not_allowed)
				(footprints allowed)
			)
			(placement
				(enabled no)
				(sheetname "")
			)
			(fill
				(thermal_gap 0.5)
				(thermal_bridge_width 0.5)
				(island_removal_mode 0)
			)
			(polygon
				(pts
					(xy 439.4073 -148.59) (xy 439.9153 -148.59) (xy 439.9153 -148.209) (xy 439.4073 -148.209)
				)
			)
		)
		(zone
			(layer "B.Cu")
			(hatch none 0.5)
			(connect_pads
				(clearance 0)
			)
			(min_thickness 0.25)
			(keepout
				(tracks allowed)
				(vias not_allowed)
				(pads allowed)
				(copperpour not_allowed)
				(footprints allowed)
			)
			(placement
				(enabled no)
				(sheetname "")
			)
			(fill
				(thermal_gap 0.5)
				(thermal_bridge_width 0.5)
				(island_removal_mode 0)
			)
			(polygon
				(pts
					(xy 439.4073 -148.209) (xy 439.9153 -148.209) (xy 439.9153 -148.59) (xy 439.4073 -148.59)
				)
			)
		)
	)
	(footprint ""
		(layer "B.Cu")
		(at 441.119006 -41.648126 180)
		(property "Reference" "R25W24"
			(at 0 0 0)
			(layer "B.SilkS")
			(hide yes)
			(effects
				(font
					(size 1.27 1.27)
				)
				(justify mirror)
			)
		)
		(property "Value" "*"
			(at -0.064008 -4.108196 180)
			(unlocked yes)
			(layer "B.Fab")
			(hide yes)
			(effects
				(font
					(size 1.27 1.016)
					(thickness 0.1524)
				)
				(justify mirror)
			)
		)
		(property "Device Type" "120R2F-GP_RCL_GP-120R2F-GP,64.A"
			(at -0.064008 -5.632196 180)
			(unlocked yes)
			(layer "B.Fab")
			(hide yes)
			(effects
				(font
					(size 1.27 1.016)
					(thickness 0.1524)
				)
				(justify mirror)
			)
		)
		(duplicate_pad_numbers_are_jumpers no)
		(fp_line
			(start 0.508 -0.9398)
			(end 0.508 0.9398)
			(stroke
				(width 0.1524)
				(type default)
			)
			(layer "B.SilkS")
		)
		(fp_line
			(start -0.508 -0.9398)
			(end 0.508 -0.9398)
			(stroke
				(width 0.1524)
				(type default)
			)
			(layer "B.SilkS")
		)
		(fp_rect
			(start 0.508 0.9398)
			(end -0.508 -0.9398)
			(stroke
				(width 0)
				(type default)
			)
			(fill no)
			(layer "B.CrtYd")
		)
		(fp_rect
			(start 0.508 0.9398)
			(end -0.508 -0.9398)
			(stroke
				(width 0)
				(type default)
			)
			(fill no)
			(layer "B.Fab")
		)
		(pad "1" smd custom
			(at 0 -0.4445)
			(size 0.1397 0.1397)
			(layers "B.Cu" "B.Mask" "B.Paste")
			(net "GND")
			(options
				(clearance outline)
				(anchor circle)
			)
			(primitives
				(gr_poly
					(pts
						(arc
							(start -0.1778 0.2794)
							(mid -0.249642 0.249642)
							(end -0.2794 0.1778)
						)
						(arc
							(start -0.2794 -0.1778)
							(mid -0.249642 -0.249642)
							(end -0.1778 -0.2794)
						)
						(arc
							(start 0.1778 -0.2794)
							(mid 0.249642 -0.249642)
							(end 0.2794 -0.1778)
						)
						(arc
							(start 0.2794 0.1778)
							(mid 0.249642 0.249642)
							(end 0.1778 0.2794)
						)
					)
					(width 0)
					(fill yes)
				)
			)
		)
		(pad "2" smd custom
			(at 0 0.4445)
			(size 0.1397 0.1397)
			(layers "B.Cu" "B.Mask" "B.Paste")
			(net "BMC_M_A12")
			(options
				(clearance outline)
				(anchor circle)
			)
			(primitives
				(gr_poly
					(pts
						(arc
							(start -0.1778 0.2794)
							(mid -0.249642 0.249642)
							(end -0.2794 0.1778)
						)
						(arc
							(start -0.2794 -0.1778)
							(mid -0.249642 -0.249642)
							(end -0.1778 -0.2794)
						)
						(arc
							(start 0.1778 -0.2794)
							(mid 0.249642 -0.249642)
							(end 0.2794 -0.1778)
						)
						(arc
							(start 0.2794 0.1778)
							(mid 0.249642 0.249642)
							(end 0.1778 0.2794)
						)
					)
					(width 0)
					(fill yes)
				)
			)
		)
	)
	(footprint ""
		(layer "B.Cu")
		(at 344.435176 -77.694536 180)
		(property "Reference" "C3P18"
			(at 0 0 0)
			(layer "B.SilkS")
			(hide yes)
			(effects
				(font
					(size 1.27 1.27)
				)
				(justify mirror)
			)
		)
		(property "Value" ""
			(at 0 0 0)
			(layer "B.Fab")
			(effects
				(font
					(size 1.27 1.27)
				)
				(justify mirror)
			)
		)
		(duplicate_pad_numbers_are_jumpers no)
		(fp_poly
			(pts
				(xy -0.3048 -0.1016) (xy -0.3048 0.9906) (xy 0.3048 0.9906) (xy 0.3048 -0.1016)
			)
			(stroke
				(width 0)
				(type default)
			)
			(fill no)
			(layer "B.CrtYd")
		)
		(fp_line
			(start 0.3048 0.9906)
			(end -0.3048 0.9906)
			(stroke
				(width 0.1)
				(type default)
			)
			(layer "B.Fab")
		)
		(fp_line
			(start 0.3048 -0.1016)
			(end 0.3048 0.9906)
			(stroke
				(width 0.1)
				(type default)
			)
			(layer "B.Fab")
		)
		(fp_line
			(start -0.3048 0.9906)
			(end -0.3048 -0.1016)
			(stroke
				(width 0.1)
				(type default)
			)
			(layer "B.Fab")
		)
		(fp_line
			(start -0.3048 -0.1016)
			(end 0.3048 -0.1016)
			(stroke
				(width 0.1)
				(type default)
			)
			(layer "B.Fab")
		)
		(pad "1" smd rect
			(at 0 0)
			(size 0.508 0.508)
			(layers "B.Cu" "B.Mask" "B.Paste")
			(net "P3E_CPU0_PE1_SS_TXP<2>")
		)
		(pad "2" smd rect
			(at 0 0.889)
			(size 0.508 0.508)
			(layers "B.Cu" "B.Mask" "B.Paste")
			(net "P3E_CPU0_PE1_PCH_TXP<2>")
		)
		(zone
			(layer "B.Cu")
			(hatch none 0.5)
			(connect_pads
				(clearance 0)
			)
			(min_thickness 0.25)
			(keepout
				(tracks allowed)
				(vias not_allowed)
				(pads allowed)
				(copperpour not_allowed)
				(footprints allowed)
			)
			(placement
				(enabled no)
				(sheetname "")
			)
			(fill
				(thermal_gap 0.5)
				(thermal_bridge_width 0.5)
				(island_removal_mode 0)
			)
			(polygon
				(pts
					(xy 344.181176 -77.948536) (xy 344.689176 -77.948536) (xy 344.689176 -78.329536) (xy 344.181176 -78.329536)
				)
			)
		)
	)
	(footprint ""
		(layer "B.Cu")
		(at 318.543432 -17.78 -90)
		(property "Reference" "C4T6"
			(at 0 0 90)
			(layer "B.SilkS")
			(hide yes)
			(effects
				(font
					(size 1.27 1.27)
				)
				(justify mirror)
			)
		)
		(property "Value" ""
			(at 0 0 90)
			(layer "B.Fab")
			(effects
				(font
					(size 1.27 1.27)
				)
				(justify mirror)
			)
		)
		(duplicate_pad_numbers_are_jumpers no)
		(fp_poly
			(pts
				(xy 0.4953 -0.2032) (xy -0.4953 -0.2032) (xy -0.4953 1.6002) (xy 0.4953 1.6002)
			)
			(stroke
				(width 0)
				(type default)
			)
			(fill no)
			(layer "B.CrtYd")
		)
		(fp_line
			(start -0.4953 1.6002)
			(end 0.4953 1.6002)
			(stroke
				(width 0.1)
				(type default)
			)
			(layer "B.Fab")
		)
		(fp_line
			(start 0.4953 1.6002)
			(end 0.4953 -0.2032)
			(stroke
				(width 0.1)
				(type default)
			)
			(layer "B.Fab")
		)
		(fp_line
			(start -0.4953 -0.2032)
			(end -0.4953 1.6002)
			(stroke
				(width 0.1)
				(type default)
			)
			(layer "B.Fab")
		)
		(fp_line
			(start 0.4953 -0.2032)
			(end -0.4953 -0.2032)
			(stroke
				(width 0.1)
				(type default)
			)
			(layer "B.Fab")
		)
		(pad "1" smd rect
			(at 0 0 90)
			(size 0.762 0.889)
			(layers "B.Cu" "B.Mask" "B.Paste")
			(net "PVPP_ABC")
		)
		(pad "2" smd rect
			(at 0 1.397 90)
			(size 0.762 0.889)
			(layers "B.Cu" "B.Mask" "B.Paste")
			(net "GND")
		)
		(zone
			(layer "B.Cu")
			(hatch none 0.5)
			(connect_pads
				(clearance 0)
			)
			(min_thickness 0.25)
			(keepout
				(tracks not_allowed)
				(vias allowed)
				(pads allowed)
				(copperpour not_allowed)
				(footprints allowed)
			)
			(placement
				(enabled no)
				(sheetname "")
			)
			(fill
				(thermal_gap 0.5)
				(thermal_bridge_width 0.5)
				(island_removal_mode 0)
			)
			(polygon
				(pts
					(xy 318.098932 -17.399) (xy 318.098932 -18.161) (xy 317.590932 -18.161) (xy 317.590932 -17.399)
				)
			)
		)
	)
	(footprint ""
		(layer "B.Cu")
		(at 494.706148 -44.533312)
		(property "Reference" "C25W79"
			(at 0.8382 -0.67818 0)
			(unlocked yes)
			(layer "B.SilkS")
			(effects
				(font
					(size 0.4064 0.254)
					(thickness 0.1524)
				)
				(justify left mirror)
			)
		)
		(property "Value" ""
			(at 0 0 0)
			(layer "B.Fab")
			(effects
				(font
					(size 1.27 1.27)
				)
				(justify mirror)
			)
		)
		(duplicate_pad_numbers_are_jumpers no)
		(fp_poly
			(pts
				(xy -0.3048 -0.1016) (xy -0.3048 0.9906) (xy 0.3048 0.9906) (xy 0.3048 -0.1016)
			)
			(stroke
				(width 0)
				(type default)
			)
			(fill no)
			(layer "B.CrtYd")
		)
		(fp_line
			(start -0.3048 -0.1016)
			(end 0.3048 -0.1016)
			(stroke
				(width 0.1)
				(type default)
			)
			(layer "B.Fab")
		)
		(fp_line
			(start -0.3048 0.9906)
			(end -0.3048 -0.1016)
			(stroke
				(width 0.1)
				(type default)
			)
			(layer "B.Fab")
		)
		(fp_line
			(start 0.3048 -0.1016)
			(end 0.3048 0.9906)
			(stroke
				(width 0.1)
				(type default)
			)
			(layer "B.Fab")
		)
		(fp_line
			(start 0.3048 0.9906)
			(end -0.3048 0.9906)
			(stroke
				(width 0.1)
				(type default)
			)
			(layer "B.Fab")
		)
		(pad "1" smd rect
			(at 0 0 180)
			(size 0.508 0.508)
			(layers "B.Cu" "B.Mask" "B.Paste")
			(net "V_IBMC_5V_DDC_SDA_J")
		)
		(pad "2" smd rect
			(at 0 0.889 180)
			(size 0.508 0.508)
			(layers "B.Cu" "B.Mask" "B.Paste")
			(net "GND")
		)
		(zone
			(layer "B.Cu")
			(hatch none 0.5)
			(connect_pads
				(clearance 0)
			)
			(min_thickness 0.25)
			(keepout
				(tracks allowed)
				(vias not_allowed)
				(pads allowed)
				(copperpour not_allowed)
				(footprints allowed)
			)
			(placement
				(enabled no)
				(sheetname "")
			)
			(fill
				(thermal_gap 0.5)
				(thermal_bridge_width 0.5)
				(island_removal_mode 0)
			)
			(polygon
				(pts
					(xy 494.960148 -44.279312) (xy 494.452148 -44.279312) (xy 494.452148 -43.898312) (xy 494.960148 -43.898312)
				)
			)
		)
		(zone
			(layer "B.Cu")
			(hatch none 0.5)
			(connect_pads
				(clearance 0)
			)
			(min_thickness 0.25)
			(keepout
				(tracks not_allowed)
				(vias allowed)
				(pads allowed)
				(copperpour not_allowed)
				(footprints allowed)
			)
			(placement
				(enabled no)
				(sheetname "")
			)
			(fill
				(thermal_gap 0.5)
				(thermal_bridge_width 0.5)
				(island_removal_mode 0)
			)
			(polygon
				(pts
					(xy 494.960148 -43.898312) (xy 494.452148 -43.898312) (xy 494.452148 -44.279312) (xy 494.960148 -44.279312)
				)
			)
		)
	)
	(footprint ""
		(layer "B.Cu")
		(at 258.2164 -140.1826 -90)
		(property "Reference" "C5G68"
			(at -1.14681 0.76708 0)
			(unlocked yes)
			(layer "B.SilkS")
			(effects
				(font
					(size 0.7874 0.5842)
					(thickness 0.1524)
				)
				(justify mirror)
			)
		)
		(property "Value" ""
			(at 0 0 90)
			(layer "B.Fab")
			(effects
				(font
					(size 1.27 1.27)
				)
				(justify mirror)
			)
		)
		(duplicate_pad_numbers_are_jumpers no)
		(fp_rect
			(start -0.4953 -0.2032)
			(end 0.4953 1.6002)
			(stroke
				(width 0)
				(type default)
			)
			(fill no)
			(layer "B.CrtYd")
		)
		(fp_line
			(start -0.4953 1.6002)
			(end 0.4953 1.6002)
			(stroke
				(width 0.1)
				(type default)
			)
			(layer "B.Fab")
		)
		(fp_line
			(start 0.4953 1.6002)
			(end 0.4953 -0.2032)
			(stroke
				(width 0.1)
				(type default)
			)
			(layer "B.Fab")
		)
		(fp_line
			(start -0.4953 -0.2032)
			(end -0.4953 1.6002)
			(stroke
				(width 0.1)
				(type default)
			)
			(layer "B.Fab")
		)
		(fp_line
			(start 0.4953 -0.2032)
			(end -0.4953 -0.2032)
			(stroke
				(width 0.1)
				(type default)
			)
			(layer "B.Fab")
		)
		(pad "1" smd rect
			(at 0 0 90)
			(size 0.762 0.889)
			(layers "B.Cu" "B.Mask" "B.Paste")
			(net "PVDDQ_DEF")
		)
		(pad "2" smd rect
			(at 0 1.397 90)
			(size 0.762 0.889)
			(layers "B.Cu" "B.Mask" "B.Paste")
			(net "GND")
		)
		(zone
			(layer "B.Cu")
			(hatch none 0.5)
			(connect_pads
				(clearance 0)
			)
			(min_thickness 0.25)
			(keepout
				(tracks not_allowed)
				(vias allowed)
				(pads allowed)
				(copperpour not_allowed)
				(footprints allowed)
			)
			(placement
				(enabled no)
				(sheetname "")
			)
			(fill
				(thermal_gap 0.5)
				(thermal_bridge_width 0.5)
				(island_removal_mode 0)
			)
			(polygon
				(pts
					(xy 257.7719 -140.5636) (xy 257.2639 -140.5636) (xy 257.2639 -139.8016) (xy 257.7719 -139.8016)
				)
			)
		)
	)
	(footprint ""
		(layer "B.Cu")
		(at 500.38 -143.002 -90)
		(property "Reference" "U6W5"
			(at 0.14986 2.621788 270)
			(unlocked yes)
			(layer "B.SilkS")
			(effects
				(font
					(size 1.27 0.964946)
					(thickness 0.000001)
				)
				(justify left mirror)
			)
		)
		(property "Value" ""
			(at 0 0 90)
			(layer "B.Fab")
			(effects
				(font
					(size 1.27 1.27)
				)
				(justify mirror)
			)
		)
		(duplicate_pad_numbers_are_jumpers no)
		(fp_circle
			(center 0.4699 -0.8382)
			(end 0.4699 -0.9652)
			(stroke
				(width 0.254)
				(type default)
			)
			(fill no)
			(layer "B.SilkS")
		)
		(fp_poly
			(pts
				(xy -0.21463 -0.450088) (xy -1.56337 -0.450088) (xy -1.56337 1.75006) (xy -0.21463 1.75006)
			)
			(stroke
				(width 0)
				(type default)
			)
			(fill no)
			(layer "B.CrtYd")
		)
		(fp_line
			(start -1.56337 1.75006)
			(end -0.21463 1.75006)
			(stroke
				(width 0.1)
				(type default)
			)
			(layer "B.Fab")
		)
		(fp_line
			(start -0.21463 1.75006)
			(end -0.21463 -0.450088)
			(stroke
				(width 0.1)
				(type default)
			)
			(layer "B.Fab")
		)
		(fp_line
			(start -1.56337 -0.450088)
			(end -1.56337 1.75006)
			(stroke
				(width 0.1)
				(type default)
			)
			(layer "B.Fab")
		)
		(fp_line
			(start -0.21463 -0.450088)
			(end -1.56337 -0.450088)
			(stroke
				(width 0.1)
				(type default)
			)
			(layer "B.Fab")
		)
		(fp_circle
			(center 0.4699 -0.8382)
			(end 0.4699 -0.9652)
			(stroke
				(width 0.254)
				(type default)
			)
			(fill no)
			(layer "B.Fab")
		)
		(pad "1" smd rect
			(at 0 0 90)
			(size 1.016 0.381)
			(layers "B.Cu" "B.Mask" "B.Paste")
			(net "DEBUG_CARD2_PRSNT")
		)
		(pad "2" smd rect
			(at 0 0.649986 90)
			(size 1.016 0.381)
			(layers "B.Cu" "B.Mask" "B.Paste")
			(net "SPA_MID_DBG_TX")
		)
		(pad "3" smd rect
			(at 0 1.299972 90)
			(size 1.016 0.381)
			(layers "B.Cu" "B.Mask" "B.Paste")
			(net "GND")
		)
		(pad "4" smd rect
			(at -1.778 1.299972 90)
			(size 1.016 0.381)
			(layers "B.Cu" "B.Mask" "B.Paste")
			(net "SPA_MID_DBG2_TX_R")
		)
		(pad "5" smd rect
			(at -1.778 0 90)
			(size 1.016 0.381)
			(layers "B.Cu" "B.Mask" "B.Paste")
			(net "P3V3_STBY")
		)
	)
)
